(kicad_pcb
	(version 20260206)
	(generator "pcbnew")
	(generator_version "10.0")
	(general
		(thickness 1.6)
		(legacy_teardrops no)
	)
	(paper "A4")
	(title_block
		(title "Bryce Canyon_F.DPB_16315-1-OCP.brd")
		(comment 1 "Bryce Canyon / footprints 1424-1431 of 2223")
	)
	(layers
		(0 "F.Cu" signal "TOP")
		(4 "In1.Cu" signal "L2GND")
		(6 "In2.Cu" signal "L3")
		(8 "In3.Cu" signal "L4GND")
		(10 "In4.Cu" signal "L5")
		(12 "In5.Cu" signal "L6VCC")
		(14 "In6.Cu" signal "L7VCC")
		(16 "In7.Cu" signal "L8")
		(18 "In8.Cu" signal "L9GND")
		(20 "In9.Cu" signal "L10")
		(22 "In10.Cu" signal "L11GND")
		(2 "B.Cu" signal "BOTTOM")
		(9 "F.Adhes" user "F.Adhesive")
		(11 "B.Adhes" user "B.Adhesive")
		(13 "F.Paste" user "Package Geometry/Pastemask Top")
		(15 "B.Paste" user "Package Geometry/Pastemask Bottom")
		(5 "F.SilkS" user "Ref Des/Silkscreen Top")
		(7 "B.SilkS" user "Ref Des/Silkscreen Bottom")
		(1 "F.Mask" user "Board Geometry/Soldermask Top")
		(3 "B.Mask" user "Board Geometry/Soldermask Bottom")
		(17 "Dwgs.User" user "User.Drawings")
		(19 "Cmts.User" user "User.Comments")
		(21 "Eco1.User" user "User.Eco1")
		(23 "Eco2.User" user "User.Eco2")
		(25 "Edge.Cuts" user "Board Geometry/Outline")
		(27 "Margin" user)
		(31 "F.CrtYd" user "Package Geometry/Place Bound Top")
		(29 "B.CrtYd" user "Package Geometry/Place Bound Bottom")
		(35 "F.Fab" user "Ref Des/Assembly Top")
		(33 "B.Fab" user "Ref Des/Assembly Bottom")
	)
	(footprint ""
		(layer "F.Cu")
		(at 247.15597 -300.038262 180)
		(property "Reference" "C159"
			(at 0 0 180)
			(layer "F.SilkS")
			(hide yes)
			(effects
				(font
					(size 1.27 1.27)
				)
			)
		)
		(property "Value" "SCD1U16V2KX-3GP"
			(at 1.1811 -2.7051 180)
			(unlocked yes)
			(layer "F.Fab")
			(hide yes)
			(effects
				(font
					(size 1.016 1.016)
					(thickness 0.1524)
				)
			)
		)
		(property "Device Type" "C402H22"
			(at 1.1811 -4.2291 180)
			(unlocked yes)
			(layer "F.Fab")
			(hide yes)
			(effects
				(font
					(size 1.016 1.016)
					(thickness 0.1524)
				)
			)
		)
		(duplicate_pad_numbers_are_jumpers no)
		(fp_rect
			(start -0.4318 0.9525)
			(end 0.4318 -0.9525)
			(stroke
				(width 0)
				(type default)
			)
			(fill no)
			(layer "F.CrtYd")
		)
		(fp_rect
			(start -0.4318 0.9525)
			(end 0.4318 -0.9525)
			(stroke
				(width 0)
				(type default)
			)
			(fill no)
			(layer "F.Fab")
		)
		(pad "1" smd custom
			(at 0 -0.4445 180)
			(size 0.1524 0.1524)
			(layers "F.Cu" "F.Mask" "F.Paste")
			(net "P3V3_STBY_A")
			(options
				(clearance outline)
				(anchor circle)
			)
			(primitives
				(gr_poly
					(pts
						(arc
							(start 0.3048 -0.2032)
							(mid 0.275042 -0.275042)
							(end 0.2032 -0.3048)
						)
						(arc
							(start -0.2032 -0.3048)
							(mid -0.275042 -0.275042)
							(end -0.3048 -0.2032)
						)
						(arc
							(start -0.3048 0.2032)
							(mid -0.275042 0.275042)
							(end -0.2032 0.3048)
						)
						(arc
							(start 0.2032 0.3048)
							(mid 0.275042 0.275042)
							(end 0.3048 0.2032)
						)
					)
					(width 0)
					(fill yes)
				)
			)
		)
		(pad "2" smd custom
			(at 0 0.4445 180)
			(size 0.1524 0.1524)
			(layers "F.Cu" "F.Mask" "F.Paste")
			(net "GND")
			(options
				(clearance outline)
				(anchor circle)
			)
			(primitives
				(gr_poly
					(pts
						(arc
							(start 0.3048 -0.2032)
							(mid 0.275042 -0.275042)
							(end 0.2032 -0.3048)
						)
						(arc
							(start -0.2032 -0.3048)
							(mid -0.275042 -0.275042)
							(end -0.3048 -0.2032)
						)
						(arc
							(start -0.3048 0.2032)
							(mid -0.275042 0.275042)
							(end -0.2032 0.3048)
						)
						(arc
							(start 0.2032 0.3048)
							(mid 0.275042 0.275042)
							(end 0.3048 0.2032)
						)
					)
					(width 0)
					(fill yes)
				)
			)
		)
	)
	(footprint ""
		(layer "F.Cu")
		(at 18.500598 -160.633918)
		(property "Reference" "R423"
			(at 0 0 0)
			(layer "F.SilkS")
			(hide yes)
			(effects
				(font
					(size 1.27 1.27)
				)
			)
		)
		(property "Value" "0R2J-2-GP"
			(at 0.064008 -3.993896 0)
			(unlocked yes)
			(layer "F.Fab")
			(hide yes)
			(effects
				(font
					(size 1.016 1.016)
					(thickness 0.1524)
				)
			)
		)
		(property "Device Type" "R402H16"
			(at 0.064008 -5.517896 0)
			(unlocked yes)
			(layer "F.Fab")
			(hide yes)
			(effects
				(font
					(size 1.016 1.016)
					(thickness 0.1524)
				)
			)
		)
		(duplicate_pad_numbers_are_jumpers no)
		(fp_line
			(start -0.508 -0.9398)
			(end -0.508 0.9398)
			(stroke
				(width 0.1524)
				(type default)
			)
			(layer "F.SilkS")
		)
		(fp_line
			(start 0.508 -0.9398)
			(end -0.508 -0.9398)
			(stroke
				(width 0.1524)
				(type default)
			)
			(layer "F.SilkS")
		)
		(fp_rect
			(start -0.508 0.9398)
			(end 0.508 -0.9398)
			(stroke
				(width 0)
				(type default)
			)
			(fill no)
			(layer "F.CrtYd")
		)
		(fp_rect
			(start -0.508 0.9398)
			(end 0.508 -0.9398)
			(stroke
				(width 0)
				(type default)
			)
			(fill no)
			(layer "F.Fab")
		)
		(pad "1" smd custom
			(at 0 -0.4445)
			(size 0.1397 0.1397)
			(layers "F.Cu" "F.Mask" "F.Paste")
			(net "SW_HDD_G12")
			(options
				(clearance outline)
				(anchor circle)
			)
			(primitives
				(gr_poly
					(pts
						(arc
							(start -0.1778 -0.2794)
							(mid -0.249642 -0.249642)
							(end -0.2794 -0.1778)
						)
						(arc
							(start -0.2794 0.1778)
							(mid -0.249642 0.249642)
							(end -0.1778 0.2794)
						)
						(arc
							(start 0.1778 0.2794)
							(mid 0.249642 0.249642)
							(end 0.2794 0.1778)
						)
						(arc
							(start 0.2794 -0.1778)
							(mid 0.249642 -0.249642)
							(end 0.1778 -0.2794)
						)
					)
					(width 0)
					(fill yes)
				)
			)
		)
		(pad "2" smd custom
			(at 0 0.4445)
			(size 0.1397 0.1397)
			(layers "F.Cu" "F.Mask" "F.Paste")
			(net "SW_HDD_R12")
			(options
				(clearance outline)
				(anchor circle)
			)
			(primitives
				(gr_poly
					(pts
						(arc
							(start -0.1778 -0.2794)
							(mid -0.249642 -0.249642)
							(end -0.2794 -0.1778)
						)
						(arc
							(start -0.2794 0.1778)
							(mid -0.249642 0.249642)
							(end -0.1778 0.2794)
						)
						(arc
							(start 0.1778 0.2794)
							(mid 0.249642 0.249642)
							(end 0.2794 0.1778)
						)
						(arc
							(start 0.2794 -0.1778)
							(mid 0.249642 -0.249642)
							(end 0.1778 -0.2794)
						)
					)
					(width 0)
					(fill yes)
				)
			)
		)
	)
	(footprint ""
		(layer "F.Cu")
		(at 469.815926 -64.683894 -90)
		(property "Reference" "C501"
			(at 0 0 270)
			(layer "F.SilkS")
			(hide yes)
			(effects
				(font
					(size 1.27 1.27)
				)
			)
		)
		(property "Value" "SC4D7U25V5KX-1-GP"
			(at -0.0762 -6.1214 270)
			(unlocked yes)
			(layer "F.Fab")
			(hide yes)
			(effects
				(font
					(size 1.016 1.016)
					(thickness 0.1524)
				)
			)
		)
		(property "Device Type" "C805H58"
			(at -0.0762 -8.1534 270)
			(unlocked yes)
			(layer "F.Fab")
			(hide yes)
			(effects
				(font
					(size 1.016 1.016)
					(thickness 0.1524)
				)
			)
		)
		(duplicate_pad_numbers_are_jumpers no)
		(fp_line
			(start 0.635 0)
			(end -0.635 0)
			(stroke
				(width 0.508)
				(type default)
			)
			(layer "F.SilkS")
		)
		(fp_rect
			(start -0.9652 1.778)
			(end 0.9652 -1.778)
			(stroke
				(width 0)
				(type default)
			)
			(fill no)
			(layer "F.CrtYd")
		)
		(fp_poly
			(pts
				(xy -0.9652 -1.778) (xy 0.9652 -1.778) (xy 0.9652 1.778) (xy -0.9652 1.778)
			)
			(stroke
				(width 0)
				(type default)
			)
			(fill no)
			(layer "F.Fab")
		)
		(pad "1" smd rect
			(at 0 -0.9652 270)
			(size 1.397 1.143)
			(layers "F.Cu" "F.Mask" "F.Paste")
			(net "P12V_HDD35")
		)
		(pad "2" smd rect
			(at 0 0.9652 270)
			(size 1.397 1.143)
			(layers "F.Cu" "F.Mask" "F.Paste")
			(net "GND")
		)
	)
	(footprint ""
		(layer "F.Cu")
		(at 368.481102 -45.735494 180)
		(property "Reference" "R856"
			(at 0 0 180)
			(layer "F.SilkS")
			(hide yes)
			(effects
				(font
					(size 1.27 1.27)
				)
			)
		)
		(property "Value" "4K7R2J-2-GP"
			(at 0.064008 -3.993896 180)
			(unlocked yes)
			(layer "F.Fab")
			(hide yes)
			(effects
				(font
					(size 1.016 1.016)
					(thickness 0.1524)
				)
			)
		)
		(property "Device Type" "R402H16"
			(at 0.064008 -5.517896 180)
			(unlocked yes)
			(layer "F.Fab")
			(hide yes)
			(effects
				(font
					(size 1.016 1.016)
					(thickness 0.1524)
				)
			)
		)
		(duplicate_pad_numbers_are_jumpers no)
		(fp_line
			(start 0.508 -0.9398)
			(end -0.508 -0.9398)
			(stroke
				(width 0.1524)
				(type default)
			)
			(layer "F.SilkS")
		)
		(fp_line
			(start -0.508 -0.9398)
			(end -0.508 0.9398)
			(stroke
				(width 0.1524)
				(type default)
			)
			(layer "F.SilkS")
		)
		(fp_rect
			(start -0.508 0.9398)
			(end 0.508 -0.9398)
			(stroke
				(width 0)
				(type default)
			)
			(fill no)
			(layer "F.CrtYd")
		)
		(fp_rect
			(start -0.508 0.9398)
			(end 0.508 -0.9398)
			(stroke
				(width 0)
				(type default)
			)
			(fill no)
			(layer "F.Fab")
		)
		(pad "1" smd custom
			(at 0 -0.4445 180)
			(size 0.1397 0.1397)
			(layers "F.Cu" "F.Mask" "F.Paste")
			(net "P12V_A")
			(options
				(clearance outline)
				(anchor circle)
			)
			(primitives
				(gr_poly
					(pts
						(arc
							(start -0.1778 -0.2794)
							(mid -0.249642 -0.249642)
							(end -0.2794 -0.1778)
						)
						(arc
							(start -0.2794 0.1778)
							(mid -0.249642 0.249642)
							(end -0.1778 0.2794)
						)
						(arc
							(start 0.1778 0.2794)
							(mid 0.249642 0.249642)
							(end 0.2794 0.1778)
						)
						(arc
							(start 0.2794 -0.1778)
							(mid 0.249642 -0.249642)
							(end 0.1778 -0.2794)
						)
					)
					(width 0)
					(fill yes)
				)
			)
		)
		(pad "2" smd custom
			(at 0 0.4445 180)
			(size 0.1397 0.1397)
			(layers "F.Cu" "F.Mask" "F.Paste")
			(net "SW_HDD_R31")
			(options
				(clearance outline)
				(anchor circle)
			)
			(primitives
				(gr_poly
					(pts
						(arc
							(start -0.1778 -0.2794)
							(mid -0.249642 -0.249642)
							(end -0.2794 -0.1778)
						)
						(arc
							(start -0.2794 0.1778)
							(mid -0.249642 0.249642)
							(end -0.1778 0.2794)
						)
						(arc
							(start 0.1778 0.2794)
							(mid 0.249642 0.249642)
							(end 0.2794 0.1778)
						)
						(arc
							(start 0.2794 -0.1778)
							(mid 0.249642 -0.249642)
							(end 0.1778 -0.2794)
						)
					)
					(width 0)
					(fill yes)
				)
			)
		)
	)
	(footprint ""
		(layer "F.Cu")
		(at 130.193796 -183.747918)
		(property "Reference" "TP77"
			(at 0 0 0)
			(layer "F.SilkS")
			(hide yes)
			(effects
				(font
					(size 1.27 1.27)
				)
			)
		)
		(property "Value" "TPAD32-GP"
			(at -0.0508 -1.6764 0)
			(unlocked yes)
			(layer "F.Fab")
			(hide yes)
			(effects
				(font
					(size 1.016 1.016)
					(thickness 0.1524)
				)
			)
		)
		(property "Device Type" "TPAD32"
			(at -0.0508 -3.2004 0)
			(unlocked yes)
			(layer "F.Fab")
			(hide yes)
			(effects
				(font
					(size 1.016 1.016)
					(thickness 0.1524)
				)
			)
		)
		(duplicate_pad_numbers_are_jumpers no)
		(fp_poly
			(pts
				(arc
					(start 0.4064 0)
					(mid -0.4064 0)
					(end 0.4064 0)
				)
			)
			(stroke
				(width 0)
				(type default)
			)
			(fill no)
			(layer "F.CrtYd")
		)
		(fp_poly
			(pts
				(arc
					(start 0.7112 0)
					(mid -0.7112 0)
					(end 0.7112 0)
				)
			)
			(stroke
				(width 0)
				(type default)
			)
			(fill no)
			(layer "F.Fab")
		)
		(pad "1" smd circle
			(at 0 0)
			(size 0.8128 0.8128)
			(layers "F.Cu" "F.Mask" "F.Paste")
			(net "ACT_HDD_15")
		)
	)
	(footprint ""
		(layer "F.Cu")
		(at 38.055804 -185.125614)
		(property "Reference" "Q264"
			(at 0 0 0)
			(layer "F.SilkS")
			(hide yes)
			(effects
				(font
					(size 1.27 1.27)
				)
			)
		)
		(property "Value" "SSM3K324R-GP"
			(at 0.127 -8.9662 0)
			(unlocked yes)
			(layer "F.Fab")
			(hide yes)
			(effects
				(font
					(size 1.016 1.016)
					(thickness 0.1524)
				)
			)
		)
		(property "Device Type" "SOT23DGS2D4H35"
			(at 0.127 -10.4902 0)
			(unlocked yes)
			(layer "F.Fab")
			(hide yes)
			(effects
				(font
					(size 1.016 1.016)
					(thickness 0.1524)
				)
			)
		)
		(duplicate_pad_numbers_are_jumpers no)
		(fp_line
			(start -1.651 -1.778)
			(end -1.651 1.778)
			(stroke
				(width 0.1524)
				(type default)
			)
			(layer "F.SilkS")
		)
		(fp_line
			(start -1.651 1.778)
			(end 1.651 1.778)
			(stroke
				(width 0.1524)
				(type default)
			)
			(layer "F.SilkS")
		)
		(fp_line
			(start 1.651 -1.778)
			(end -1.651 -1.778)
			(stroke
				(width 0.1524)
				(type default)
			)
			(layer "F.SilkS")
		)
		(fp_line
			(start 1.651 1.778)
			(end 1.651 -1.778)
			(stroke
				(width 0.1524)
				(type default)
			)
			(layer "F.SilkS")
		)
		(fp_poly
			(pts
				(xy -1.778 1.8796) (xy -1.778 -1.8796) (xy 1.778 -1.8796) (xy 1.778 1.8796)
			)
			(stroke
				(width 0)
				(type default)
			)
			(fill no)
			(layer "F.CrtYd")
		)
		(fp_poly
			(pts
				(xy -1.778 1.8796) (xy -1.778 -1.8796) (xy 1.778 -1.8796) (xy 1.778 1.8796)
			)
			(stroke
				(width 0)
				(type default)
			)
			(fill no)
			(layer "F.Fab")
		)
		(pad "D" smd custom
			(at 0 -0.9525)
			(size 0.1905 0.1905)
			(layers "F.Cu" "F.Mask" "F.Paste")
			(net "DRV_ACT_1_N")
			(options
				(clearance outline)
				(anchor circle)
			)
			(primitives
				(gr_poly
					(pts
						(arc
							(start -0.1778 0.5715)
							(mid -0.321484 0.511984)
							(end -0.381 0.3683)
						)
						(arc
							(start -0.381 -0.3683)
							(mid -0.321484 -0.511984)
							(end -0.1778 -0.5715)
						)
						(arc
							(start 0.1778 -0.5715)
							(mid 0.321484 -0.511984)
							(end 0.381 -0.3683)
						)
						(arc
							(start 0.381 0.3683)
							(mid 0.321484 0.511984)
							(end 0.1778 0.5715)
						)
					)
					(width 0)
					(fill yes)
				)
			)
		)
		(pad "G" smd custom
			(at -0.98425 0.9525)
			(size 0.1905 0.1905)
			(layers "F.Cu" "F.Mask" "F.Paste")
			(net "DRIVE_A_1_ACT")
			(options
				(clearance outline)
				(anchor circle)
			)
			(primitives
				(gr_poly
					(pts
						(arc
							(start -0.1778 0.5715)
							(mid -0.321484 0.511984)
							(end -0.381 0.3683)
						)
						(arc
							(start -0.381 -0.3683)
							(mid -0.321484 -0.511984)
							(end -0.1778 -0.5715)
						)
						(arc
							(start 0.1778 -0.5715)
							(mid 0.321484 -0.511984)
							(end 0.381 -0.3683)
						)
						(arc
							(start 0.381 0.3683)
							(mid 0.321484 0.511984)
							(end 0.1778 0.5715)
						)
					)
					(width 0)
					(fill yes)
				)
			)
		)
		(pad "S" smd custom
			(at 0.98425 0.9525)
			(size 0.1905 0.1905)
			(layers "F.Cu" "F.Mask" "F.Paste")
			(net "GND")
			(options
				(clearance outline)
				(anchor circle)
			)
			(primitives
				(gr_poly
					(pts
						(arc
							(start -0.1778 0.5715)
							(mid -0.321484 0.511984)
							(end -0.381 0.3683)
						)
						(arc
							(start -0.381 -0.3683)
							(mid -0.321484 -0.511984)
							(end -0.1778 -0.5715)
						)
						(arc
							(start 0.1778 -0.5715)
							(mid 0.321484 -0.511984)
							(end 0.381 -0.3683)
						)
						(arc
							(start 0.381 0.3683)
							(mid 0.321484 0.511984)
							(end 0.1778 0.5715)
						)
					)
					(width 0)
					(fill yes)
				)
			)
		)
	)
	(footprint ""
		(layer "F.Cu")
		(at 263.137142 -210.617562 180)
		(property "Reference" "R371"
			(at 0 0 180)
			(layer "F.SilkS")
			(hide yes)
			(effects
				(font
					(size 1.27 1.27)
				)
			)
		)
		(property "Value" "10KR2F-2-GP"
			(at 0.064008 -3.993896 180)
			(unlocked yes)
			(layer "F.Fab")
			(hide yes)
			(effects
				(font
					(size 1.016 1.016)
					(thickness 0.1524)
				)
			)
		)
		(property "Device Type" "R402H16"
			(at 0.064008 -5.517896 180)
			(unlocked yes)
			(layer "F.Fab")
			(hide yes)
			(effects
				(font
					(size 1.016 1.016)
					(thickness 0.1524)
				)
			)
		)
		(duplicate_pad_numbers_are_jumpers no)
		(fp_line
			(start 0.508 -0.9398)
			(end -0.508 -0.9398)
			(stroke
				(width 0.1524)
				(type default)
			)
			(layer "F.SilkS")
		)
		(fp_line
			(start -0.508 -0.9398)
			(end -0.508 0.9398)
			(stroke
				(width 0.1524)
				(type default)
			)
			(layer "F.SilkS")
		)
		(fp_rect
			(start -0.508 0.9398)
			(end 0.508 -0.9398)
			(stroke
				(width 0)
				(type default)
			)
			(fill no)
			(layer "F.CrtYd")
		)
		(fp_rect
			(start -0.508 0.9398)
			(end 0.508 -0.9398)
			(stroke
				(width 0)
				(type default)
			)
			(fill no)
			(layer "F.Fab")
		)
		(pad "1" smd custom
			(at 0 -0.4445 180)
			(size 0.1397 0.1397)
			(layers "F.Cu" "F.Mask" "F.Paste")
			(net "P3V3_STBY_A")
			(options
				(clearance outline)
				(anchor circle)
			)
			(primitives
				(gr_poly
					(pts
						(arc
							(start -0.1778 -0.2794)
							(mid -0.249642 -0.249642)
							(end -0.2794 -0.1778)
						)
						(arc
							(start -0.2794 0.1778)
							(mid -0.249642 0.249642)
							(end -0.1778 0.2794)
						)
						(arc
							(start 0.1778 0.2794)
							(mid 0.249642 0.249642)
							(end 0.2794 0.1778)
						)
						(arc
							(start 0.2794 -0.1778)
							(mid 0.249642 -0.249642)
							(end 0.1778 -0.2794)
						)
					)
					(width 0)
					(fill yes)
				)
			)
		)
		(pad "2" smd custom
			(at 0 0.4445 180)
			(size 0.1397 0.1397)
			(layers "F.Cu" "F.Mask" "F.Paste")
			(net "I2C_DPB_BUFF_EN")
			(options
				(clearance outline)
				(anchor circle)
			)
			(primitives
				(gr_poly
					(pts
						(arc
							(start -0.1778 -0.2794)
							(mid -0.249642 -0.249642)
							(end -0.2794 -0.1778)
						)
						(arc
							(start -0.2794 0.1778)
							(mid -0.249642 0.249642)
							(end -0.1778 0.2794)
						)
						(arc
							(start 0.1778 0.2794)
							(mid 0.249642 0.249642)
							(end 0.2794 0.1778)
						)
						(arc
							(start 0.2794 -0.1778)
							(mid 0.249642 -0.249642)
							(end 0.1778 -0.2794)
						)
					)
					(width 0)
					(fill yes)
				)
			)
		)
	)
	(footprint ""
		(layer "F.Cu")
		(at 255.389634 -8.215122 90)
		(property "Reference" "TP216"
			(at 0 0 90)
			(layer "F.SilkS")
			(hide yes)
			(effects
				(font
					(size 1.27 1.27)
				)
			)
		)
		(property "Value" "TPAD32-GP"
			(at -0.0508 -1.6764 90)
			(unlocked yes)
			(layer "F.Fab")
			(hide yes)
			(effects
				(font
					(size 1.016 1.016)
					(thickness 0.1524)
				)
			)
		)
		(property "Device Type" "TPAD32"
			(at -0.0508 -3.2004 90)
			(unlocked yes)
			(layer "F.Fab")
			(hide yes)
			(effects
				(font
					(size 1.016 1.016)
					(thickness 0.1524)
				)
			)
		)
		(duplicate_pad_numbers_are_jumpers no)
		(fp_poly
			(pts
				(arc
					(start 0 0.4064)
					(mid 0 -0.4064)
					(end 0 0.4064)
				)
			)
			(stroke
				(width 0)
				(type default)
			)
			(fill no)
			(layer "F.CrtYd")
		)
		(fp_poly
			(pts
				(arc
					(start 0 0.7112)
					(mid 0 -0.7112)
					(end 0 0.7112)
				)
			)
			(stroke
				(width 0)
				(type default)
			)
			(fill no)
			(layer "F.Fab")
		)
		(pad "1" smd circle
			(at 0 0 90)
			(size 0.8128 0.8128)
			(layers "F.Cu" "F.Mask" "F.Paste")
			(net "TP_COMP_A_NCSI_TXD1")
		)
	)
)
